(kicad_pcb
	(version 20241229)
	(generator "pcbnew")
	(generator_version "9.0")
	(general
		(thickness 1.61)
		(legacy_teardrops no)
	)
	(paper "A3")
	(title_block
		(title "SO-DIMM DDR5 Tester")
		(date "2025-11-26")
		(rev "1.3.0")
		(comment 9 "footprints 370-375 of 627")
	)
	(layers
		(0 "F.Cu" signal)
		(4 "In1.Cu" power)
		(6 "In2.Cu" mixed)
		(8 "In3.Cu" power)
		(10 "In4.Cu" mixed)
		(12 "In5.Cu" power)
		(14 "In6.Cu" mixed)
		(16 "In7.Cu" power)
		(18 "In8.Cu" power)
		(20 "In9.Cu" mixed)
		(22 "In10.Cu" power)
		(2 "B.Cu" signal)
		(9 "F.Adhes" user "F.Adhesive")
		(11 "B.Adhes" user "B.Adhesive")
		(13 "F.Paste" user)
		(15 "B.Paste" user)
		(5 "F.SilkS" user "F.Silkscreen")
		(7 "B.SilkS" user "B.Silkscreen")
		(1 "F.Mask" user)
		(3 "B.Mask" user)
		(17 "Dwgs.User" user "User.Drawings")
		(19 "Cmts.User" user "User.Comments")
		(21 "Eco1.User" user "User.Eco1")
		(23 "Eco2.User" user "User.Eco2")
		(25 "Edge.Cuts" user)
		(27 "Margin" user)
		(31 "F.CrtYd" user "F.Courtyard")
		(29 "B.CrtYd" user "B.Courtyard")
		(35 "F.Fab" user)
		(33 "B.Fab" user)
	)
	(footprint "antmicro-footprints:R_0402_1005Metric"
		(layer "B.Cu")
		(at 97.425501 161.576 90)
		(descr "Resistor SMD 0402")
		(tags "resistor SMD 0402")
		(property "Reference" "R103"
			(at -1.122484 0.772697 270)
			(layer "B.SilkS")
			(hide yes)
			(effects
				(font
					(size 0.7 0.7)
					(thickness 0.15)
				)
				(justify left bottom mirror)
			)
		)
		(property "Value" "R_10k_0402"
			(at -1.011843 -1.772047 270)
			(layer "B.Fab")
			(effects
				(font
					(size 0.7 0.7)
					(thickness 0.15)
				)
				(justify left bottom mirror)
			)
		)
		(property "Datasheet" "https://www.bourns.com/docs/product-datasheets/cr.pdf"
			(at 0 0 90)
			(layer "F.Fab")
			(hide yes)
			(effects
				(font
					(size 1.27 1.27)
					(thickness 0.15)
				)
			)
		)
		(property "Author" "Antmicro"
			(at 259.001501 64.150499 0)
			(layer "B.Fab")
			(hide yes)
			(effects
				(font
					(size 1 1)
					(thickness 0.15)
				)
				(justify mirror)
			)
		)
		(property "License" "Apache-2.0"
			(at 259.001501 64.150499 0)
			(layer "B.Fab")
			(hide yes)
			(effects
				(font
					(size 1 1)
					(thickness 0.15)
				)
				(justify mirror)
			)
		)
		(property "MPN" "CR0402-FX-1002GLF"
			(at 259.001501 64.150499 0)
			(layer "B.Fab")
			(hide yes)
			(effects
				(font
					(size 1 1)
					(thickness 0.15)
				)
				(justify mirror)
			)
		)
		(property "Manufacturer" "Bourns"
			(at 259.001501 64.150499 0)
			(layer "B.Fab")
			(hide yes)
			(effects
				(font
					(size 1 1)
					(thickness 0.15)
				)
				(justify mirror)
			)
		)
		(property "Tolerance" "1%"
			(at 259.001501 64.150499 0)
			(layer "B.Fab")
			(hide yes)
			(effects
				(font
					(size 1 1)
					(thickness 0.15)
				)
				(justify mirror)
			)
		)
		(property "Val" "10k"
			(at 259.001501 64.150499 0)
			(layer "B.Fab")
			(hide yes)
			(effects
				(font
					(size 1 1)
					(thickness 0.15)
				)
				(justify mirror)
			)
		)
		(sheetname "/Ethernet/")
		(sheetfile "ethernet.kicad_sch")
		(attr smd)
		(fp_rect
			(start -0.93 0.47)
			(end 0.93 -0.47)
			(stroke
				(width 0.05)
				(type solid)
			)
			(fill no)
			(layer "B.CrtYd")
		)
		(fp_rect
			(start -0.5 0.25)
			(end 0.5 -0.25)
			(stroke
				(width 0.15)
				(type solid)
			)
			(fill no)
			(layer "B.Fab")
		)
		(pad "1" smd roundrect
			(at -0.485 0 90)
			(size 0.59 0.64)
			(layers "B.Cu" "B.Mask" "B.Paste")
			(roundrect_rratio 0.25)
			(net 675 "/Ethernet/ETH.RXD2")
			(pintype "passive")
		)
		(pad "2" smd roundrect
			(at 0.485 0 90)
			(size 0.59 0.64)
			(layers "B.Cu" "B.Mask" "B.Paste")
			(roundrect_rratio 0.25)
			(net 200 "+3V3")
			(pintype "passive")
		)
	)
	(footprint "antmicro-footprints:R_0402_1005Metric"
		(layer "B.Cu")
		(at 144.399998 142.4 90)
		(descr "Resistor SMD 0402")
		(tags "resistor SMD 0402")
		(property "Reference" "R29"
			(at 3 0.3 270)
			(layer "B.SilkS")
			(effects
				(font
					(size 0.7 0.7)
					(thickness 0.15)
				)
				(justify left bottom mirror)
			)
		)
		(property "Value" "R_0R_0402"
			(at -1.011843 -1.772047 270)
			(layer "B.Fab")
			(effects
				(font
					(size 0.7 0.7)
					(thickness 0.15)
				)
				(justify left bottom mirror)
			)
		)
		(property "Datasheet" "https://industrial.panasonic.com/cdbs/www-data/pdf/RDA0000/AOA0000C301.pdf"
			(at 0 0 90)
			(layer "F.Fab")
			(hide yes)
			(effects
				(font
					(size 1.27 1.27)
					(thickness 0.15)
				)
			)
		)
		(property "Author" "Antmicro"
			(at 286.799998 -1.999998 0)
			(layer "B.Fab")
			(hide yes)
			(effects
				(font
					(size 1 1)
					(thickness 0.15)
				)
				(justify mirror)
			)
		)
		(property "Current" "1A"
			(at 286.799998 -1.999998 0)
			(layer "B.Fab")
			(hide yes)
			(effects
				(font
					(size 1 1)
					(thickness 0.15)
				)
				(justify mirror)
			)
		)
		(property "License" "Apache-2.0"
			(at 286.799998 -1.999998 0)
			(layer "B.Fab")
			(hide yes)
			(effects
				(font
					(size 1 1)
					(thickness 0.15)
				)
				(justify mirror)
			)
		)
		(property "MPN" "ERJ2GE0R00X"
			(at 286.799998 -1.999998 0)
			(layer "B.Fab")
			(hide yes)
			(effects
				(font
					(size 1 1)
					(thickness 0.15)
				)
				(justify mirror)
			)
		)
		(property "Manufacturer" "Panasonic"
			(at 286.799998 -1.999998 0)
			(layer "B.Fab")
			(hide yes)
			(effects
				(font
					(size 1 1)
					(thickness 0.15)
				)
				(justify mirror)
			)
		)
		(property "Tolerance" ""
			(at 286.799998 -1.999998 0)
			(layer "B.Fab")
			(hide yes)
			(effects
				(font
					(size 1 1)
					(thickness 0.15)
				)
				(justify mirror)
			)
		)
		(property "Val" "0R"
			(at 286.799998 -1.999998 0)
			(layer "B.Fab")
			(hide yes)
			(effects
				(font
					(size 1 1)
					(thickness 0.15)
				)
				(justify mirror)
			)
		)
		(sheetname "/DDR5 SODIMM/")
		(sheetfile "ddr5-sodimm.kicad_sch")
		(attr exclude_from_pos_files exclude_from_bom dnp)
		(fp_rect
			(start -0.93 0.47)
			(end 0.93 -0.47)
			(stroke
				(width 0.05)
				(type solid)
			)
			(fill no)
			(layer "B.CrtYd")
		)
		(fp_rect
			(start -0.5 0.25)
			(end 0.5 -0.25)
			(stroke
				(width 0.15)
				(type solid)
			)
			(fill no)
			(layer "B.Fab")
		)
		(pad "1" smd roundrect
			(at -0.485 0 90)
			(size 0.59 0.64)
			(layers "B.Cu" "B.Mask" "B.Paste")
			(roundrect_rratio 0.25)
			(net 1 "GND")
			(pintype "passive")
		)
		(pad "2" smd roundrect
			(at 0.485 0 90)
			(size 0.59 0.64)
			(layers "B.Cu" "B.Mask" "B.Paste")
			(roundrect_rratio 0.25)
			(net 173 "/DDR5 SODIMM/RFU3")
			(pintype "passive")
		)
	)
	(footprint "antmicro-footprints:C_0402_1005Metric"
		(layer "B.Cu")
		(at 117.650501 172.866)
		(descr "Capacitor SMD 0402")
		(tags "capacitor SMD 0402")
		(property "Reference" "C3"
			(at 0 0.699 180)
			(layer "B.SilkS")
			(hide yes)
			(effects
				(font
					(size 0.7 0.7)
					(thickness 0.15)
				)
				(justify left bottom mirror)
			)
		)
		(property "Value" "C_100n_0402"
			(at -1.022927 -2.155213 180)
			(layer "B.Fab")
			(effects
				(font
					(size 0.7 0.7)
					(thickness 0.15)
				)
				(justify left bottom mirror)
			)
		)
		(property "Datasheet" "https://www.murata.com/products/productdetail?partno=GRM155R61H104KE14%23"
			(at 0 0 0)
			(layer "F.Fab")
			(hide yes)
			(effects
				(font
					(size 1.27 1.27)
					(thickness 0.15)
				)
			)
		)
		(property "Author" "Antmicro"
			(at 0 0 0)
			(layer "B.Fab")
			(hide yes)
			(effects
				(font
					(size 1 1)
					(thickness 0.15)
				)
				(justify mirror)
			)
		)
		(property "Dielectric" "X5R"
			(at 0 0 0)
			(layer "B.Fab")
			(hide yes)
			(effects
				(font
					(size 1 1)
					(thickness 0.15)
				)
				(justify mirror)
			)
		)
		(property "License" "Apache-2.0"
			(at 0 0 0)
			(layer "B.Fab")
			(hide yes)
			(effects
				(font
					(size 1 1)
					(thickness 0.15)
				)
				(justify mirror)
			)
		)
		(property "MPN" "GRM155R61H104KE14D"
			(at 0 0 0)
			(layer "B.Fab")
			(hide yes)
			(effects
				(font
					(size 1 1)
					(thickness 0.15)
				)
				(justify mirror)
			)
		)
		(property "Manufacturer" "Murata"
			(at 0 0 0)
			(layer "B.Fab")
			(hide yes)
			(effects
				(font
					(size 1 1)
					(thickness 0.15)
				)
				(justify mirror)
			)
		)
		(property "Val" "100n"
			(at 0 0 0)
			(layer "B.Fab")
			(hide yes)
			(effects
				(font
					(size 1 1)
					(thickness 0.15)
				)
				(justify mirror)
			)
		)
		(property "Voltage" "50V"
			(at 0 0 0)
			(layer "B.Fab")
			(hide yes)
			(effects
				(font
					(size 1 1)
					(thickness 0.15)
				)
				(justify mirror)
			)
		)
		(sheetname "/HyperRAM + QSPI Flash/")
		(sheetfile "hyperram-flash.kicad_sch")
		(attr smd)
		(fp_rect
			(start -0.9659 0.481258)
			(end 0.9649 -0.458742)
			(stroke
				(width 0.05)
				(type solid)
			)
			(fill no)
			(layer "B.CrtYd")
		)
		(fp_line
			(start -0.499 -0.248)
			(end -0.499 0.25)
			(stroke
				(width 0.15)
				(type solid)
			)
			(layer "B.Fab")
		)
		(fp_line
			(start -0.499 0.25)
			(end 0.499 0.25)
			(stroke
				(width 0.15)
				(type solid)
			)
			(layer "B.Fab")
		)
		(fp_line
			(start 0.499 -0.248)
			(end -0.499 -0.248)
			(stroke
				(width 0.15)
				(type solid)
			)
			(layer "B.Fab")
		)
		(fp_line
			(start 0.499 0.25)
			(end 0.499 -0.248)
			(stroke
				(width 0.15)
				(type solid)
			)
			(layer "B.Fab")
		)
		(pad "1" smd roundrect
			(at -0.484 0)
			(size 0.59 0.64)
			(layers "B.Cu" "B.Mask" "B.Paste")
			(roundrect_rratio 0.25)
			(net 200 "+3V3")
			(pintype "passive")
		)
		(pad "2" smd roundrect
			(at 0.484 0)
			(size 0.59 0.64)
			(layers "B.Cu" "B.Mask" "B.Paste")
			(roundrect_rratio 0.25)
			(net 1 "GND")
			(pintype "passive")
		)
	)
	(footprint "antmicro-footprints:C_0402_1005Metric"
		(layer "B.Cu")
		(at 147.875501 162.301 180)
		(descr "Capacitor SMD 0402 (1005 Metric), square (rectangular) end terminal, IPC_7351 nominal, (Body size source: IPC-SM-782 page 76, https://www.pcb-3d.com/wordpress/wp-content/uploads/ipc-sm-782a_amendment_1_and_2.pdf)")
		(tags "capacitor 0402")
		(property "Reference" "C87"
			(at 0 1.17 0)
			(layer "B.SilkS")
			(hide yes)
			(effects
				(font
					(size 0.7 0.7)
					(thickness 0.15)
				)
				(justify left bottom mirror)
			)
		)
		(property "Value" "C_100n_0402"
			(at 0 -1.169 0)
			(layer "B.Fab")
			(effects
				(font
					(size 0.7 0.7)
					(thickness 0.15)
				)
				(justify left bottom mirror)
			)
		)
		(property "Datasheet" "https://www.murata.com/products/productdetail?partno=GRM155R61H104KE14%23"
			(at 0 0 180)
			(layer "F.Fab")
			(hide yes)
			(effects
				(font
					(size 1.27 1.27)
					(thickness 0.15)
				)
			)
		)
		(property "Author" "Antmicro"
			(at 295.751002 324.602 0)
			(layer "B.Fab")
			(hide yes)
			(effects
				(font
					(size 1 1)
					(thickness 0.15)
				)
				(justify mirror)
			)
		)
		(property "Dielectric" "X5R"
			(at 295.751002 324.602 0)
			(layer "B.Fab")
			(hide yes)
			(effects
				(font
					(size 1 1)
					(thickness 0.15)
				)
				(justify mirror)
			)
		)
		(property "License" "Apache-2.0"
			(at 295.751002 324.602 0)
			(layer "B.Fab")
			(hide yes)
			(effects
				(font
					(size 1 1)
					(thickness 0.15)
				)
				(justify mirror)
			)
		)
		(property "MPN" "GRM155R61H104KE14D"
			(at 295.751002 324.602 0)
			(layer "B.Fab")
			(hide yes)
			(effects
				(font
					(size 1 1)
					(thickness 0.15)
				)
				(justify mirror)
			)
		)
		(property "Manufacturer" "Murata"
			(at 295.751002 324.602 0)
			(layer "B.Fab")
			(hide yes)
			(effects
				(font
					(size 1 1)
					(thickness 0.15)
				)
				(justify mirror)
			)
		)
		(property "Val" "100n"
			(at 295.751002 324.602 0)
			(layer "B.Fab")
			(hide yes)
			(effects
				(font
					(size 1 1)
					(thickness 0.15)
				)
				(justify mirror)
			)
		)
		(property "Voltage" "50V"
			(at 295.751002 324.602 0)
			(layer "B.Fab")
			(hide yes)
			(effects
				(font
					(size 1 1)
					(thickness 0.15)
				)
				(justify mirror)
			)
		)
		(sheetname "/FPGA power/")
		(sheetfile "fpga-power.kicad_sch")
		(attr smd)
		(fp_rect
			(start -0.9656 0.4572)
			(end 0.9652 -0.4828)
			(stroke
				(width 0.05)
				(type solid)
			)
			(fill no)
			(layer "B.CrtYd")
		)
		(fp_line
			(start 0.498 0.25)
			(end 0.498 -0.248)
			(stroke
				(width 0.15)
				(type solid)
			)
			(layer "B.Fab")
		)
		(fp_line
			(start 0.498 -0.248)
			(end -0.5 -0.248)
			(stroke
				(width 0.15)
				(type solid)
			)
			(layer "B.Fab")
		)
		(fp_line
			(start -0.5 0.25)
			(end 0.498 0.25)
			(stroke
				(width 0.15)
				(type solid)
			)
			(layer "B.Fab")
		)
		(fp_line
			(start -0.5 -0.248)
			(end -0.5 0.25)
			(stroke
				(width 0.15)
				(type solid)
			)
			(layer "B.Fab")
		)
		(pad "1" smd roundrect
			(at -0.5 0 90)
			(size 0.6 0.6)
			(layers "B.Cu" "B.Mask" "B.Paste")
			(roundrect_rratio 0.25)
			(net 1 "GND")
			(pintype "passive")
		)
		(pad "2" smd roundrect
			(at 0.498 0 180)
			(size 0.6 0.6)
			(layers "B.Cu" "B.Mask" "B.Paste")
			(roundrect_rratio 0.25)
			(net 206 "+1V1")
			(pintype "passive")
		)
	)
	(footprint "antmicro-footprints:R_0402_1005Metric"
		(layer "B.Cu")
		(at 180.8 197.4 180)
		(descr "Resistor SMD 0402")
		(tags "resistor SMD 0402")
		(property "Reference" "R150"
			(at -3.95 -0.5 0)
			(layer "B.SilkS")
			(effects
				(font
					(size 0.7 0.7)
					(thickness 0.15)
				)
				(justify left bottom mirror)
			)
		)
		(property "Value" "R_4k7_0402"
			(at -1.011843 -1.772047 0)
			(layer "B.Fab")
			(effects
				(font
					(size 0.7 0.7)
					(thickness 0.15)
				)
				(justify left bottom mirror)
			)
		)
		(property "Datasheet" "https://www.bourns.com/docs/product-datasheets/cr.pdf"
			(at 0 0 180)
			(layer "F.Fab")
			(hide yes)
			(effects
				(font
					(size 1.27 1.27)
					(thickness 0.15)
				)
			)
		)
		(property "Author" "Antmicro"
			(at 361.6 394.8 0)
			(layer "B.Fab")
			(hide yes)
			(effects
				(font
					(size 1 1)
					(thickness 0.15)
				)
				(justify mirror)
			)
		)
		(property "License" "Apache-2.0"
			(at 361.6 394.8 0)
			(layer "B.Fab")
			(hide yes)
			(effects
				(font
					(size 1 1)
					(thickness 0.15)
				)
				(justify mirror)
			)
		)
		(property "MPN" "CR0402-FX-4701GLF"
			(at 361.6 394.8 0)
			(layer "B.Fab")
			(hide yes)
			(effects
				(font
					(size 1 1)
					(thickness 0.15)
				)
				(justify mirror)
			)
		)
		(property "Manufacturer" "Bourns"
			(at 361.6 394.8 0)
			(layer "B.Fab")
			(hide yes)
			(effects
				(font
					(size 1 1)
					(thickness 0.15)
				)
				(justify mirror)
			)
		)
		(property "Tolerance" "1%"
			(at 361.6 394.8 0)
			(layer "B.Fab")
			(hide yes)
			(effects
				(font
					(size 1 1)
					(thickness 0.15)
				)
				(justify mirror)
			)
		)
		(property "Val" "4k7"
			(at 361.6 394.8 0)
			(layer "B.Fab")
			(hide yes)
			(effects
				(font
					(size 1 1)
					(thickness 0.15)
				)
				(justify mirror)
			)
		)
		(sheetname "/I^{2}C/")
		(sheetfile "i2c.kicad_sch")
		(attr smd)
		(fp_rect
			(start -0.93 0.47)
			(end 0.93 -0.47)
			(stroke
				(width 0.05)
				(type solid)
			)
			(fill no)
			(layer "B.CrtYd")
		)
		(fp_rect
			(start -0.5 0.25)
			(end 0.5 -0.25)
			(stroke
				(width 0.15)
				(type solid)
			)
			(fill no)
			(layer "B.Fab")
		)
		(pad "1" smd roundrect
			(at -0.485 0 180)
			(size 0.59 0.64)
			(layers "B.Cu" "B.Mask" "B.Paste")
			(roundrect_rratio 0.25)
			(net 200 "+3V3")
			(pintype "passive")
		)
		(pad "2" smd roundrect
			(at 0.485 0 180)
			(size 0.59 0.64)
			(layers "B.Cu" "B.Mask" "B.Paste")
			(roundrect_rratio 0.25)
			(net 688 "/FPGA bank 14/FPGA_PWR.SDA")
			(pintype "passive")
		)
	)
	(footprint "antmicro-footprints:C_0402_1005Metric"
		(layer "B.Cu")
		(at 144.875501 173.301 180)
		(descr "Capacitor SMD 0402 (1005 Metric), square (rectangular) end terminal, IPC_7351 nominal, (Body size source: IPC-SM-782 page 76, https://www.pcb-3d.com/wordpress/wp-content/uploads/ipc-sm-782a_amendment_1_and_2.pdf)")
		(tags "capacitor 0402")
		(property "Reference" "C77"
			(at 0 1.17 0)
			(layer "B.SilkS")
			(hide yes)
			(effects
				(font
					(size 0.7 0.7)
					(thickness 0.15)
				)
				(justify left bottom mirror)
			)
		)
		(property "Value" "C_100n_0402"
			(at 0 -1.169 0)
			(layer "B.Fab")
			(effects
				(font
					(size 0.7 0.7)
					(thickness 0.15)
				)
				(justify left bottom mirror)
			)
		)
		(property "Datasheet" "https://www.murata.com/products/productdetail?partno=GRM155R61H104KE14%23"
			(at 0 0 180)
			(layer "F.Fab")
			(hide yes)
			(effects
				(font
					(size 1.27 1.27)
					(thickness 0.15)
				)
			)
		)
		(property "Author" "Antmicro"
			(at 289.751002 346.602 0)
			(layer "B.Fab")
			(hide yes)
			(effects
				(font
					(size 1 1)
					(thickness 0.15)
				)
				(justify mirror)
			)
		)
		(property "Dielectric" "X5R"
			(at 289.751002 346.602 0)
			(layer "B.Fab")
			(hide yes)
			(effects
				(font
					(size 1 1)
					(thickness 0.15)
				)
				(justify mirror)
			)
		)
		(property "License" "Apache-2.0"
			(at 289.751002 346.602 0)
			(layer "B.Fab")
			(hide yes)
			(effects
				(font
					(size 1 1)
					(thickness 0.15)
				)
				(justify mirror)
			)
		)
		(property "MPN" "GRM155R61H104KE14D"
			(at 289.751002 346.602 0)
			(layer "B.Fab")
			(hide yes)
			(effects
				(font
					(size 1 1)
					(thickness 0.15)
				)
				(justify mirror)
			)
		)
		(property "Manufacturer" "Murata"
			(at 289.751002 346.602 0)
			(layer "B.Fab")
			(hide yes)
			(effects
				(font
					(size 1 1)
					(thickness 0.15)
				)
				(justify mirror)
			)
		)
		(property "Val" "100n"
			(at 289.751002 346.602 0)
			(layer "B.Fab")
			(hide yes)
			(effects
				(font
					(size 1 1)
					(thickness 0.15)
				)
				(justify mirror)
			)
		)
		(property "Voltage" "50V"
			(at 289.751002 346.602 0)
			(layer "B.Fab")
			(hide yes)
			(effects
				(font
					(size 1 1)
					(thickness 0.15)
				)
				(justify mirror)
			)
		)
		(sheetname "/FPGA power/")
		(sheetfile "fpga-power.kicad_sch")
		(attr smd)
		(fp_rect
			(start -0.9656 0.4572)
			(end 0.9652 -0.4828)
			(stroke
				(width 0.05)
				(type solid)
			)
			(fill no)
			(layer "B.CrtYd")
		)
		(fp_line
			(start 0.498 0.25)
			(end 0.498 -0.248)
			(stroke
				(width 0.15)
				(type solid)
			)
			(layer "B.Fab")
		)
		(fp_line
			(start 0.498 -0.248)
			(end -0.5 -0.248)
			(stroke
				(width 0.15)
				(type solid)
			)
			(layer "B.Fab")
		)
		(fp_line
			(start -0.5 0.25)
			(end 0.498 0.25)
			(stroke
				(width 0.15)
				(type solid)
			)
			(layer "B.Fab")
		)
		(fp_line
			(start -0.5 -0.248)
			(end -0.5 0.25)
			(stroke
				(width 0.15)
				(type solid)
			)
			(layer "B.Fab")
		)
		(pad "1" smd roundrect
			(at -0.5 0 90)
			(size 0.6 0.6)
			(layers "B.Cu" "B.Mask" "B.Paste")
			(roundrect_rratio 0.25)
			(net 1 "GND")
			(pintype "passive")
		)
		(pad "2" smd roundrect
			(at 0.498 0 180)
			(size 0.6 0.6)
			(layers "B.Cu" "B.Mask" "B.Paste")
			(roundrect_rratio 0.25)
			(net 188 "+1V8")
			(pintype "passive")
		)
	)
)
